FILE_TYPE = MULTI_PHYS_TABLE;

PART 'CONN4_HFK1040L0P1L7H'

{========================================================================================}
:VALUE                    | PART_TYPE | MATERIAL | PART_NUMBER      = STANDARD        | LIFECYCLE      | PART_NUMBER   | JEDEC_TYPE        | DESCRIPTION                               | MANUFTR | MANUF_PN           | RD_CMPLS_LVL | CMPLS_LVL | CLASS | DIP_SMD | FROM_PJ       | DATA                       | FP_ECN                 | EE_CHECK_LIST | CREATOR | CREATEDAY  | PSL | STATUS | ESD_CDM | ESD_HBM | ESD_MM | MSD  | PIN_LENGTH_LONG_PIN | PIN_LENGTH_SHORT_PIN ;
{========================================================================================}
 'CONN4_HFK1040-L0P1L-7H' | 'THLF'    | 'IO'     | 'DFHD04MS460'(!) = ''              | ''             | 'DFHD04MS460' |'HEADER1X4BHXA'| 'CONN DIP HEADER 4P 1R MS(P2,H6)'         | 'FOX'   | 'HFK1040-L0P1L-7H' | 'EP(V1)'     | 'EP(V1)'  | 'IO'  | 'DIP'   | 'A5R-BINGLIN' | 'FOX_HFK1040-L0P1L-7H.pdf' | ''                     | ''            | ''      | '20190308' | ''  | ''     | 'NA'    | 'NA'    | 'NA'   | 'NA' | '65 MILS'           | '134 MILS'          
 'CONN4_HFK1040-L0P1L-7H' | 'THLF'    | 'EMPTY'  | 'DFHD04MS460'(!) = ''              | ''             | 'DFHD04MS460' |'HEADER1X4BHXA'| 'CONN DIP HEADER 4P 1R MS(P2,H6)'         | 'FOX'   | 'HFK1040-L0P1L-7H' | 'EP(V1)'     | 'EP(V1)'  | 'IO'  | 'DIP'   | 'A5R-BINGLIN' | 'FOX_HFK1040-L0P1L-7H.pdf' | ''                     | ''            | ''      | '20190308' | ''  | ''     | 'NA'    | 'NA'    | 'NA'   | 'NA' | '65 MILS'           | '134 MILS'          
 'CONN4_HFK1040-L0P1L-7H' | 'THLF'    | 'IO'     | 'SP_DFHD04MS460'(!) = ''               | ''               | 'DFHD04MS460' |'G_HEADER1X4BHXA'| 'CONN DIP HEADER 4P 1R MS(P2,H6)_FOR SEL' | 'FOX'   | 'HFK1040-L0P1L-7H' | 'EP(V1)'     | 'EP(V1)'  | 'IO'  | 'DIP'   | 'S8Z-VINCENT' | 'FOX_HFK1040-L0P1L-7H.pdf' | 'HFK1040-L0P1L-7H.msg' | ''            | ''      | '20221130' | ''  | ''     | ''      | ''      | ''     | ''   | '65 MILS'           | '134 MILS'          
 'CONN4_HFK1040-L0P1L-7H' | 'THLF'    | 'EMPTY'  | 'SP_DFHD04MS460'(!) = ''               | ''               | 'DFHD04MS460' |'G_HEADER1X4BHXA'| 'CONN DIP HEADER 4P 1R MS(P2,H6)_FOR SEL' | 'FOX'   | 'HFK1040-L0P1L-7H' | 'EP(V1)'     | 'EP(V1)'  | 'IO'  | 'DIP'   | 'S8Z-VINCENT' | 'FOX_HFK1040-L0P1L-7H.pdf' | 'HFK1040-L0P1L-7H.msg' | ''            | ''      | '20221130' | ''  | ''     | ''      | ''      | ''     | ''   | '65 MILS'           | '134 MILS'          

END_PART

END.

